# T6G (Grand Teton) — schematic netlist excerpt (pin names and nets, part order shuffled) for the footprints in the layout excerpt that follows; sources: Cadence DE-HDL packaged netlist, KiCad conversion of 04192023_DAF0TMB3IC0_F0TG_MB_C_brd_V02_OCP.brd

U148  SN74AVC4T774PWR  IC  pkg TSSOP16XC  page 172
  DIR1  = P3V3_AUX
  DIR2  = P3V3_AUX
  A1  = JTAG_SCM_MUX_TCK
  A2  = JTAG_SCM_MUX_TMS
  A3  = JTAG_SCM_TRST_N
  A4  = JTAG_SCM_DBREQ_N
  DIR3  = P3V3_AUX
  DIR4  = P3V3_AUX
  OE  = JTAG_BMC_OE_N
  GND  = GND
  B4  = JTAG_DBREQ_R_N
  B3  = JTAG_TRST_R_N
  B2  = JTAG_TMS_R
  B1  = JTAG_TCK_R
  VCCB  = PVDD18_S5_P0
  VCCA  = P3V3_AUX

PC212  Q_CAP  1UF 25V 10% X6S  pkg C0402  page 209 : A = PVDD18_S5_P0_VCC ; B = GND

(kicad_pcb
	(version 20260206)
	(generator "pcbnew")
	(generator_version "10.0")
	(general
		(thickness 1.6)
		(legacy_teardrops no)
	)
	(paper "A4")
	(title_block
		(title "04192023_DAF0TMB3IC0_F0TG_MB_C_brd_V02_OCP.brd")
		(comment 1 "Grand Teton / footprints 2618-2619 of 8354")
	)
	(layers
		(0 "F.Cu" signal "TOP")
		(4 "In1.Cu" signal "GND")
		(6 "In2.Cu" signal "IN1")
		(8 "In3.Cu" signal "GND1")
		(10 "In4.Cu" signal "IN2")
		(12 "In5.Cu" signal "GND2")
		(14 "In6.Cu" signal "IN3")
		(16 "In7.Cu" signal "GND3")
		(18 "In8.Cu" signal "VCC")
		(20 "In9.Cu" signal "VCC1")
		(22 "In10.Cu" signal "GND4")
		(24 "In11.Cu" signal "IN4")
		(26 "In12.Cu" signal "GND5")
		(28 "In13.Cu" signal "IN5")
		(30 "In14.Cu" signal "GND6")
		(32 "In15.Cu" signal "IN6")
		(34 "In16.Cu" signal "GND7")
		(2 "B.Cu" signal "BOTTOM")
		(9 "F.Adhes" user "F.Adhesive")
		(11 "B.Adhes" user "B.Adhesive")
		(13 "F.Paste" user "Package Geometry/Pastemask Top")
		(15 "B.Paste" user "Package Geometry/Pastemask Bottom")
		(5 "F.SilkS" user "Ref Des/Silkscreen Top")
		(7 "B.SilkS" user "Ref Des/Silkscreen Bottom")
		(1 "F.Mask" user "Board Geometry/Soldermask Top")
		(3 "B.Mask" user "Board Geometry/Soldermask Bottom")
		(17 "Dwgs.User" user "User.Drawings")
		(19 "Cmts.User" user "User.Comments")
		(21 "Eco1.User" user "User.Eco1")
		(23 "Eco2.User" user "User.Eco2")
		(25 "Edge.Cuts" user "Board Geometry/Outline")
		(27 "Margin" user)
		(31 "F.CrtYd" user "Package Geometry/Place Bound Top")
		(29 "B.CrtYd" user "Package Geometry/Place Bound Bottom")
		(35 "F.Fab" user "Ref Des/Assembly Top")
		(33 "B.Fab" user "Ref Des/Assembly Bottom")
	)
	(footprint ""
		(layer "F.Cu")
		(at 267.068046 -106.847894 180)
		(property "Reference" "U148"
			(at 1.889252 3.59664 0)
			(unlocked yes)
			(layer "F.SilkS")
			(effects
				(font
					(size 0.7874 0.5842)
					(thickness 0.1524)
				)
				(justify left)
			)
		)
		(property "Value" ""
			(at 0 0 180)
			(layer "F.Fab")
			(effects
				(font
					(size 1.27 1.27)
				)
			)
		)
		(duplicate_pad_numbers_are_jumpers no)
		(fp_line
			(start 1.868932 2.549906)
			(end 1.868932 -2.549906)
			(stroke
				(width 0.1524)
				(type default)
			)
			(layer "F.SilkS")
		)
		(fp_line
			(start 1.868932 -2.549906)
			(end 1.025906 -2.549906)
			(stroke
				(width 0.1524)
				(type default)
			)
			(layer "F.SilkS")
		)
		(fp_line
			(start 1.025906 -2.549906)
			(end 0 -1.524)
			(stroke
				(width 0.1524)
				(type default)
			)
			(layer "F.SilkS")
		)
		(fp_line
			(start 0 -1.524)
			(end -1.025906 -2.549906)
			(stroke
				(width 0.1524)
				(type default)
			)
			(layer "F.SilkS")
		)
		(fp_line
			(start -1.025906 -2.549906)
			(end -1.868932 -2.549906)
			(stroke
				(width 0.1524)
				(type default)
			)
			(layer "F.SilkS")
		)
		(fp_line
			(start -1.868932 2.549906)
			(end 1.868932 2.549906)
			(stroke
				(width 0.1524)
				(type default)
			)
			(layer "F.SilkS")
		)
		(fp_line
			(start -1.868932 -2.549906)
			(end -1.868932 2.549906)
			(stroke
				(width 0.1524)
				(type default)
			)
			(layer "F.SilkS")
		)
		(fp_poly
			(pts
				(xy -3.7592 -2.295398) (xy -4.7752 -1.787398) (xy -4.7752 -2.803398)
			)
			(stroke
				(width 0)
				(type default)
			)
			(fill yes)
			(layer "F.SilkS")
		)
		(fp_line
			(start 2.249932 2.549906)
			(end 2.249932 -2.549906)
			(stroke
				(width 0.1)
				(type default)
			)
			(layer "F.Fab")
		)
		(fp_line
			(start 2.249932 -2.549906)
			(end -2.249932 -2.549906)
			(stroke
				(width 0.1)
				(type default)
			)
			(layer "F.Fab")
		)
		(fp_line
			(start -2.249932 2.549906)
			(end 2.249932 2.549906)
			(stroke
				(width 0.1)
				(type default)
			)
			(layer "F.Fab")
		)
		(fp_line
			(start -2.249932 -2.549906)
			(end -2.249932 2.549906)
			(stroke
				(width 0.1)
				(type default)
			)
			(layer "F.Fab")
		)
		(fp_poly
			(pts
				(xy -4.7752 -1.787398) (xy -4.7752 -2.803398) (xy -3.7592 -2.295398)
			)
			(stroke
				(width 0)
				(type default)
			)
			(fill yes)
			(layer "F.Fab")
		)
		(pad "1" smd rect
			(at -2.800096 -2.275078 90)
			(size 0.3556 1.6002)
			(layers "F.Cu" "F.Mask" "F.Paste")
			(net "P3V3_AUX")
		)
		(pad "2" smd rect
			(at -2.800096 -1.625092 90)
			(size 0.3556 1.6002)
			(layers "F.Cu" "F.Mask" "F.Paste")
			(net "P3V3_AUX")
		)
		(pad "3" smd rect
			(at -2.800096 -0.975106 90)
			(size 0.3556 1.6002)
			(layers "F.Cu" "F.Mask" "F.Paste")
			(net "JTAG_SCM_MUX_TCK")
		)
		(pad "4" smd rect
			(at -2.800096 -0.32512 90)
			(size 0.3556 1.6002)
			(layers "F.Cu" "F.Mask" "F.Paste")
			(net "JTAG_SCM_MUX_TMS")
		)
		(pad "5" smd rect
			(at -2.800096 0.32512 90)
			(size 0.3556 1.6002)
			(layers "F.Cu" "F.Mask" "F.Paste")
			(net "JTAG_SCM_TRST_N")
		)
		(pad "6" smd rect
			(at -2.800096 0.975106 90)
			(size 0.3556 1.6002)
			(layers "F.Cu" "F.Mask" "F.Paste")
			(net "JTAG_SCM_DBREQ_N")
		)
		(pad "7" smd rect
			(at -2.800096 1.625092 90)
			(size 0.3556 1.6002)
			(layers "F.Cu" "F.Mask" "F.Paste")
			(net "P3V3_AUX")
		)
		(pad "8" smd rect
			(at -2.800096 2.275078 90)
			(size 0.3556 1.6002)
			(layers "F.Cu" "F.Mask" "F.Paste")
			(net "P3V3_AUX")
		)
		(pad "9" smd rect
			(at 2.800096 2.275078 90)
			(size 0.3556 1.6002)
			(layers "F.Cu" "F.Mask" "F.Paste")
			(net "JTAG_BMC_OE_N")
		)
		(pad "10" smd rect
			(at 2.800096 1.625092 90)
			(size 0.3556 1.6002)
			(layers "F.Cu" "F.Mask" "F.Paste")
			(net "GND")
		)
		(pad "11" smd rect
			(at 2.800096 0.975106 90)
			(size 0.3556 1.6002)
			(layers "F.Cu" "F.Mask" "F.Paste")
			(net "JTAG_DBREQ_R_N")
		)
		(pad "12" smd rect
			(at 2.800096 0.32512 90)
			(size 0.3556 1.6002)
			(layers "F.Cu" "F.Mask" "F.Paste")
			(net "JTAG_TRST_R_N")
		)
		(pad "13" smd rect
			(at 2.800096 -0.32512 90)
			(size 0.3556 1.6002)
			(layers "F.Cu" "F.Mask" "F.Paste")
			(net "JTAG_TMS_R")
		)
		(pad "14" smd rect
			(at 2.800096 -0.975106 90)
			(size 0.3556 1.6002)
			(layers "F.Cu" "F.Mask" "F.Paste")
			(net "JTAG_TCK_R")
		)
		(pad "15" smd rect
			(at 2.800096 -1.625092 90)
			(size 0.3556 1.6002)
			(layers "F.Cu" "F.Mask" "F.Paste")
			(net "PVDD18_S5_P0")
		)
		(pad "16" smd rect
			(at 2.800096 -2.275078 90)
			(size 0.3556 1.6002)
			(layers "F.Cu" "F.Mask" "F.Paste")
			(net "P3V3_AUX")
		)
	)
	(footprint ""
		(layer "F.Cu")
		(at 338.41944 -142.28953 -90)
		(property "Reference" "PC212"
			(at 0 0 270)
			(layer "F.SilkS")
			(hide yes)
			(effects
				(font
					(size 1.27 1.27)
				)
			)
		)
		(property "Value" ""
			(at 0 0 270)
			(layer "F.Fab")
			(effects
				(font
					(size 1.27 1.27)
				)
			)
		)
		(duplicate_pad_numbers_are_jumpers no)
		(fp_line
			(start -0.7874 0.4064)
			(end -0.7874 -0.4064)
			(stroke
				(width 0.1524)
				(type default)
			)
			(layer "F.SilkS")
		)
		(fp_line
			(start 0.7874 0.4064)
			(end -0.7874 0.4064)
			(stroke
				(width 0.1524)
				(type default)
			)
			(layer "F.SilkS")
		)
		(fp_line
			(start -0.7874 -0.4064)
			(end 0.7874 -0.4064)
			(stroke
				(width 0.1524)
				(type default)
			)
			(layer "F.SilkS")
		)
		(fp_line
			(start 0.7874 -0.4064)
			(end 0.7874 0.4064)
			(stroke
				(width 0.1524)
				(type default)
			)
			(layer "F.SilkS")
		)
		(fp_line
			(start -0.67945 0.3048)
			(end -0.67945 -0.305054)
			(stroke
				(width 0.1)
				(type default)
			)
			(layer "F.Fab")
		)
		(fp_line
			(start -0.12065 0.3048)
			(end -0.67945 0.3048)
			(stroke
				(width 0.1)
				(type default)
			)
			(layer "F.Fab")
		)
		(fp_line
			(start 0.120396 0.3048)
			(end 0.120396 0.2794)
			(stroke
				(width 0.1)
				(type default)
			)
			(layer "F.Fab")
		)
		(fp_line
			(start 0.67945 0.3048)
			(end 0.120396 0.3048)
			(stroke
				(width 0.1)
				(type default)
			)
			(layer "F.Fab")
		)
		(fp_line
			(start -0.12065 0.2794)
			(end -0.12065 0.3048)
			(stroke
				(width 0.1)
				(type default)
			)
			(layer "F.Fab")
		)
		(fp_line
			(start 0.120396 0.2794)
			(end -0.12065 0.2794)
			(stroke
				(width 0.1)
				(type default)
			)
			(layer "F.Fab")
		)
		(fp_line
			(start -0.12065 -0.2794)
			(end 0.12065 -0.2794)
			(stroke
				(width 0.1)
				(type default)
			)
			(layer "F.Fab")
		)
		(fp_line
			(start 0.12065 -0.2794)
			(end 0.12065 -0.3048)
			(stroke
				(width 0.1)
				(type default)
			)
			(layer "F.Fab")
		)
		(fp_line
			(start 0.12065 -0.3048)
			(end 0.67945 -0.3048)
			(stroke
				(width 0.1)
				(type default)
			)
			(layer "F.Fab")
		)
		(fp_line
			(start 0.67945 -0.3048)
			(end 0.67945 0.3048)
			(stroke
				(width 0.1)
				(type default)
			)
			(layer "F.Fab")
		)
		(fp_line
			(start -0.67945 -0.305054)
			(end -0.12065 -0.305054)
			(stroke
				(width 0.1)
				(type default)
			)
			(layer "F.Fab")
		)
		(fp_line
			(start -0.12065 -0.305054)
			(end -0.12065 -0.2794)
			(stroke
				(width 0.1)
				(type default)
			)
			(layer "F.Fab")
		)
		(pad "1" smd circle
			(at -0.40005 0 270)
			(size 0 0)
			(layers "F.Cu" "F.Mask" "F.Paste")
			(net "PVDD18_S5_P0_VCC")
		)
		(pad "2" smd circle
			(at 0.40005 0 270)
			(size 0 0)
			(layers "F.Cu" "F.Mask" "F.Paste")
			(net "GND")
		)
	)
)
